FILE_TYPE = MACRO_DRAWING;
SET COLOR_WIRE YELLOW;
SET COLOR_PROP MONO;
SET COLOR_DOT WHITE;
SET COLOR_ARC YELLOW;
SET COLOR_BODY GREEN;
SET COLOR_NOTE MONO;
SET PROP_DISPLAY VALUE;
SET PAGE_NUMBER P97;
FORCEADD OFFPAGE..3
(-275 4225);
FORCEPROP 2 LAST $XR0 55 
J 0
(-61 4225);
DISPLAY 0.638298 (-61 4225);
PAINT MONO (-61 4225);
FORCEPROP 2 LAST CDS_LIB mstr_standard
J 0
(-275 4225);
PAINT ORANGE (-275 4225);
DISPLAY INVISIBLE (-275 4225);
FORCEPROP 1 LAST OFFPAGE TRUE
J 0
(50 4100);
PAINT GREEN (50 4100);
DISPLAY INVISIBLE (50 4100);
FORCEPROP 1 LAST COMMENT_BODY TRUE
J 0
(-325 4125);
DISPLAY 1.170213 (-325 4125);
PAINT PEACH (-325 4125);
DISPLAY INVISIBLE (-325 4125);
FORCEPROP 2 LAST PATH I22
J 0
(-50 4275);
DISPLAY 1.021277 (-50 4275);
PAINT ORANGE (-50 4275);
DISPLAY INVISIBLE (-50 4275);
FORCEADD RES..1
(-2000 4225);
FORCEPROP 1 LASTPIN (-2100 4225) $PN 1
J 0
(-2088 4237);
DISPLAY 0.617021 (-2088 4237);
PAINT WHITE (-2088 4237);
FORCEPROP 1 LAST TOLERANCE 5%
J 0
(-2075 4175);
DISPLAY 0.617021 (-2075 4175);
PAINT SKYBLUE (-2075 4175);
FORCEPROP 1 LAST LOCATION R3D18
J 0
(-2050 4275);
DISPLAY 0.617021 (-2050 4275);
PAINT AQUA (-2050 4275);
FORCEPROP 1 LAST PART_NUMBER G21497-005
J 0
(-2150 4125);
DISPLAY 0.617021 (-2150 4125);
PAINT BLUE (-2150 4125);
FORCEPROP 1 LAST VALUE 0.0
J 2
(-2100 4175);
DISPLAY 0.617021 (-2100 4175);
PAINT SKYBLUE (-2100 4175);
FORCEPROP 1 LAST PACK_TYPE 0402
J 0
(-1975 4175);
DISPLAY 0.617021 (-1975 4175);
PAINT SKYBLUE (-1975 4175);
FORCEPROP 1 LAST MATERIAL CHIP
J 0
(-1800 4125);
DISPLAY 0.617021 (-1800 4125);
PAINT SKYBLUE (-1800 4125);
FORCEPROP 1 LAST WATTAGE 1/16W
J 2
(-1625 4175);
DISPLAY 0.617021 (-1625 4175);
PAINT SKYBLUE (-1625 4175);
FORCEPROP 1 LASTPIN (-1900 4225) $PN 2
J 0
(-1938 4237);
DISPLAY 0.617021 (-1938 4237);
PAINT WHITE (-1938 4237);
FORCEPROP 2 LAST BOM_COST PROC_SIDEBAND
J 0
(-2000 4225);
PAINT WHITE (-2000 4225);
DISPLAY INVISIBLE (-2000 4225);
FORCEPROP 2 LAST CDS_LIB mstr_discrete
J 0
(-2000 4225);
PAINT ORANGE (-2000 4225);
DISPLAY INVISIBLE (-2000 4225);
FORCEPROP 2 LAST CDS_SEC 1
J 0
(-2050 4425);
DISPLAY 1.404255 (-2050 4425);
PAINT ORANGE (-2050 4425);
DISPLAY INVISIBLE (-2050 4425);
FORCEPROP 2 LAST $SEC 1
J 0
(-2050 4425);
DISPLAY 0.936170 (-2050 4425);
PAINT MONO (-2050 4425);
DISPLAY INVISIBLE (-2050 4425);
FORCEPROP 2 LAST CDS_LOCATION R3D18
J 0
(-2050 4275);
DISPLAY 0.617021 (-2050 4275);
PAINT AQUA (-2050 4275);
DISPLAY INVISIBLE (-2050 4275);
FORCEPROP 1 LAST PATH I33
J 0
(-2050 4375);
DISPLAY 0.978723 (-2050 4375);
PAINT WHITE (-2050 4375);
DISPLAY INVISIBLE (-2050 4375);
FORCEPROP 2 LAST ROOM PROC_SIDEBAND
J 0
(-2050 4375);
PAINT WHITE (-2050 4375);
DISPLAY INVISIBLE (-2050 4375);
FORCEADD OFFPAGE..6
(-3400 4225);
FORCEPROP 2 LAST $XR0 21 
J 0
(-3649 4225);
DISPLAY 0.638298 (-3649 4225);
PAINT MONO (-3649 4225);
FORCEPROP 2 LAST $XR1 157 
J 0
(-3649 4261);
DISPLAY 0.638298 (-3649 4261);
PAINT MONO (-3649 4261);
FORCEPROP 2 LAST CDS_LIB mstr_standard
J 0
(-3400 4225);
PAINT ORANGE (-3400 4225);
DISPLAY INVISIBLE (-3400 4225);
FORCEPROP 1 LAST OFFPAGE TRUE
J 0
(-3075 4100);
PAINT GREEN (-3075 4100);
DISPLAY INVISIBLE (-3075 4100);
FORCEPROP 1 LAST COMMENT_BODY TRUE
J 0
(-3300 4150);
DISPLAY 1.170213 (-3300 4150);
PAINT PEACH (-3300 4150);
DISPLAY INVISIBLE (-3300 4150);
FORCEPROP 2 LAST PATH I34
J 0
(-3625 4275);
DISPLAY 1.021277 (-3625 4275);
PAINT ORANGE (-3625 4275);
DISPLAY INVISIBLE (-3625 4275);
FORCEADD PVCCIO_CPU0..1
(-2700 4775);
FORCEPROP 3 LASTPIN (-2700 4725) SIG_NAME PVCCIO_CPU0\g
J 0
(-2690 4735);
DISPLAY 0.659574 (-2690 4735);
PAINT MONO (-2690 4735);
DISPLAY INVISIBLE (-2690 4735);
FORCEPROP 1 LAST VOLTAGE 1.1V
J 0
(-2745 4732);
DISPLAY 0.340426 (-2745 4732);
PAINT SKYBLUE (-2745 4732);
DISPLAY INVISIBLE (-2745 4732);
FORCEPROP 2 LAST CDS_LIB mstr_symbols
J 0
(-2700 4775);
PAINT ORANGE (-2700 4775);
DISPLAY INVISIBLE (-2700 4775);
FORCEPROP 1 LAST BODY_TYPE PLUMBING
J 0
(-2745 4732);
DISPLAY 0.340426 (-2745 4732);
PAINT GREEN (-2745 4732);
DISPLAY INVISIBLE (-2745 4732);
FORCEPROP 1 LAST PATH I41
J 0
(-2650 4800);
DISPLAY 0.872340 (-2650 4800);
PAINT AQUA (-2650 4800);
DISPLAY INVISIBLE (-2650 4800);
FORCEPROP 1 LAST HDL_POWER PVCCIO_CPU0
J 1
(-2700 4825);
DISPLAY 0.872340 (-2700 4825);
PAINT GREEN (-2700 4825);
DISPLAY INVISIBLE (-2700 4825);
FORCEADD RES..2
(-2700 4525);
FORCEPROP 1 LAST LOCATION R4R4
J 0
(-2655 4650);
DISPLAY 0.617021 (-2655 4650);
PAINT AQUA (-2655 4650);
FORCEPROP 1 LAST PART_NUMBER G21796-009
J 0
(-2660 4400);
DISPLAY 0.617021 (-2660 4400);
PAINT BLUE (-2660 4400);
FORCEPROP 1 LAST VALUE 150.0
J 0
(-2655 4600);
DISPLAY 0.617021 (-2655 4600);
PAINT SKYBLUE (-2655 4600);
FORCEPROP 1 LAST TOLERANCE 1%
J 0
(-2655 4550);
DISPLAY 0.617021 (-2655 4550);
PAINT SKYBLUE (-2655 4550);
FORCEPROP 1 LAST PACK_TYPE 0402
J 0
(-2660 4350);
DISPLAY 0.617021 (-2660 4350);
PAINT SKYBLUE (-2660 4350);
FORCEPROP 1 LAST MATERIAL CHIP
J 0
(-2660 4450);
DISPLAY 0.617021 (-2660 4450);
PAINT SKYBLUE (-2660 4450);
FORCEPROP 1 LAST WATTAGE 1/16W
J 0
(-2660 4500);
DISPLAY 0.617021 (-2660 4500);
PAINT SKYBLUE (-2660 4500);
FORCEPROP 1 LASTPIN (-2700 4425) $PN 2
J 0
(-2695 4435);
DISPLAY 0.617021 (-2695 4435);
PAINT WHITE (-2695 4435);
FORCEPROP 1 LASTPIN (-2700 4625) $PN 1
J 0
(-2695 4587);
DISPLAY 0.617021 (-2695 4587);
PAINT WHITE (-2695 4587);
FORCEPROP 2 LAST CDS_LIB mstr_discrete
J 0
(-2700 4525);
PAINT ORANGE (-2700 4525);
DISPLAY INVISIBLE (-2700 4525);
FORCEPROP 2 LAST CDS_SEC 1
J 0
(-2650 4750);
DISPLAY 1.404255 (-2650 4750);
PAINT ORANGE (-2650 4750);
DISPLAY INVISIBLE (-2650 4750);
FORCEPROP 2 LAST $SEC 1
J 0
(-2650 4750);
DISPLAY 0.936170 (-2650 4750);
PAINT MONO (-2650 4750);
DISPLAY INVISIBLE (-2650 4750);
FORCEPROP 2 LAST CDS_LOCATION R4R4
J 0
(-2655 4650);
DISPLAY 0.617021 (-2655 4650);
PAINT AQUA (-2655 4650);
DISPLAY INVISIBLE (-2655 4650);
FORCEPROP 1 LAST PATH I42
J 0
(-2650 4700);
DISPLAY 0.978723 (-2650 4700);
PAINT WHITE (-2650 4700);
DISPLAY INVISIBLE (-2650 4700);
FORCEPROP 2 LAST ROOM PROC_SIDEBAND
J 0
(-2655 4690);
DISPLAY 0.787234 (-2655 4690);
PAINT WHITE (-2655 4690);
DISPLAY INVISIBLE (-2655 4690);
FORCEADD RES..2
(-1200 4525);
FORCEPROP 1 LAST LOCATION R7P20
J 0
(-1155 4650);
DISPLAY 0.617021 (-1155 4650);
PAINT AQUA (-1155 4650);
FORCEPROP 1 LAST PART_NUMBER G21796-009
J 0
(-1160 4400);
DISPLAY 0.617021 (-1160 4400);
PAINT BLUE (-1160 4400);
FORCEPROP 1 LAST VALUE 150.0
J 0
(-1155 4600);
DISPLAY 0.617021 (-1155 4600);
PAINT SKYBLUE (-1155 4600);
FORCEPROP 1 LAST TOLERANCE 1%
J 0
(-1155 4550);
DISPLAY 0.617021 (-1155 4550);
PAINT SKYBLUE (-1155 4550);
FORCEPROP 1 LAST PACK_TYPE 0402
J 0
(-1160 4350);
DISPLAY 0.617021 (-1160 4350);
PAINT SKYBLUE (-1160 4350);
FORCEPROP 1 LAST MATERIAL CHIP
J 0
(-1160 4450);
DISPLAY 0.617021 (-1160 4450);
PAINT SKYBLUE (-1160 4450);
FORCEPROP 1 LAST WATTAGE 1/16W
J 0
(-1160 4500);
DISPLAY 0.617021 (-1160 4500);
PAINT SKYBLUE (-1160 4500);
FORCEPROP 1 LASTPIN (-1200 4425) $PN 2
J 0
(-1195 4435);
DISPLAY 0.617021 (-1195 4435);
PAINT WHITE (-1195 4435);
FORCEPROP 1 LASTPIN (-1200 4625) $PN 1
J 0
(-1195 4587);
DISPLAY 0.617021 (-1195 4587);
PAINT WHITE (-1195 4587);
FORCEPROP 2 LAST CDS_LIB mstr_discrete
J 0
(-1200 4525);
PAINT ORANGE (-1200 4525);
DISPLAY INVISIBLE (-1200 4525);
FORCEPROP 2 LAST CDS_SEC 1
J 0
(-1150 4750);
DISPLAY 1.404255 (-1150 4750);
PAINT ORANGE (-1150 4750);
DISPLAY INVISIBLE (-1150 4750);
FORCEPROP 2 LAST $SEC 1
J 0
(-1150 4750);
DISPLAY 0.936170 (-1150 4750);
PAINT MONO (-1150 4750);
DISPLAY INVISIBLE (-1150 4750);
FORCEPROP 2 LAST CDS_LOCATION R7P20
J 0
(-1155 4650);
DISPLAY 0.617021 (-1155 4650);
PAINT AQUA (-1155 4650);
DISPLAY INVISIBLE (-1155 4650);
FORCEPROP 1 LAST PATH I44
J 0
(-1150 4700);
DISPLAY 0.978723 (-1150 4700);
PAINT WHITE (-1150 4700);
DISPLAY INVISIBLE (-1150 4700);
FORCEPROP 2 LAST ROOM PROC_SIDEBAND
J 0
(-1155 4690);
DISPLAY 0.787234 (-1155 4690);
PAINT WHITE (-1155 4690);
DISPLAY INVISIBLE (-1155 4690);
FORCEADD PVCCIO_CPU0..1
(-3100 1625);
FORCEPROP 3 LASTPIN (-3100 1575) SIG_NAME PVCCIO_CPU0\g
J 0
(-3090 1585);
DISPLAY 0.659574 (-3090 1585);
PAINT MONO (-3090 1585);
DISPLAY INVISIBLE (-3090 1585);
FORCEPROP 1 LAST VOLTAGE 1.1V
J 0
(-3145 1582);
DISPLAY 0.340426 (-3145 1582);
PAINT SKYBLUE (-3145 1582);
DISPLAY INVISIBLE (-3145 1582);
FORCEPROP 2 LAST CDS_LIB mstr_symbols
J 0
(-3100 1625);
PAINT ORANGE (-3100 1625);
DISPLAY INVISIBLE (-3100 1625);
FORCEPROP 1 LAST BODY_TYPE PLUMBING
J 0
(-3145 1582);
DISPLAY 0.340426 (-3145 1582);
PAINT GREEN (-3145 1582);
DISPLAY INVISIBLE (-3145 1582);
FORCEPROP 1 LAST PATH I71
J 0
(-3050 1650);
DISPLAY 0.872340 (-3050 1650);
PAINT AQUA (-3050 1650);
DISPLAY INVISIBLE (-3050 1650);
FORCEPROP 1 LAST HDL_POWER PVCCIO_CPU0
J 1
(-3100 1675);
DISPLAY 0.872340 (-3100 1675);
PAINT GREEN (-3100 1675);
DISPLAY INVISIBLE (-3100 1675);
FORCEADD RES..1
(-2625 1425);
FORCEPROP 1 LAST LOCATION R4P21
J 0
(-2675 1475);
DISPLAY 0.617021 (-2675 1475);
PAINT AQUA (-2675 1475);
FORCEPROP 1 LAST PART_NUMBER G21796-294
J 0
(-3050 1375);
DISPLAY 0.617021 (-3050 1375);
PAINT BLUE (-3050 1375);
FORCEPROP 1 LAST VALUE 240
J 2
(-2675 1375);
DISPLAY 0.617021 (-2675 1375);
PAINT SKYBLUE (-2675 1375);
FORCEPROP 1 LAST TOLERANCE 1.0%
J 0
(-2575 1375);
DISPLAY 0.617021 (-2575 1375);
PAINT SKYBLUE (-2575 1375);
FORCEPROP 1 LAST PACK_TYPE 0402
J 0
(-2250 1375);
DISPLAY 0.617021 (-2250 1375);
PAINT SKYBLUE (-2250 1375);
FORCEPROP 1 LAST MATERIAL CHIP
J 0
(-2150 1375);
DISPLAY 0.617021 (-2150 1375);
PAINT SKYBLUE (-2150 1375);
FORCEPROP 1 LAST WATTAGE 1/16W
J 2
(-2300 1375);
DISPLAY 0.617021 (-2300 1375);
PAINT SKYBLUE (-2300 1375);
FORCEPROP 1 LASTPIN (-2525 1425) $PN 2
J 0
(-2563 1437);
DISPLAY 0.617021 (-2563 1437);
PAINT WHITE (-2563 1437);
FORCEPROP 1 LASTPIN (-2725 1425) $PN 1
J 0
(-2713 1437);
DISPLAY 0.617021 (-2713 1437);
PAINT WHITE (-2713 1437);
FORCEPROP 2 LAST SEC_TYPE 0402
J 0
(-2675 1625);
DISPLAY 1.021277 (-2675 1625);
PAINT ORANGE (-2675 1625);
DISPLAY INVISIBLE (-2675 1625);
FORCEPROP 2 LAST CDS_LIB mstr_discrete
J 0
(-2625 1425);
PAINT ORANGE (-2625 1425);
DISPLAY INVISIBLE (-2625 1425);
FORCEPROP 0 LAST BOM_COST PROC_SIDEBAND
J 0
(-2675 1675);
DISPLAY 1.021277 (-2675 1675);
PAINT WHITE (-2675 1675);
DISPLAY INVISIBLE (-2675 1675);
FORCEPROP 2 LAST SEC 1
J 0
(-2675 1625);
DISPLAY 0.680851 (-2675 1625);
PAINT MONO (-2675 1625);
DISPLAY INVISIBLE (-2675 1625);
FORCEPROP 2 LAST CDS_LOCATION R4P21
J 0
(-2675 1475);
DISPLAY 0.617021 (-2675 1475);
PAINT AQUA (-2675 1475);
DISPLAY INVISIBLE (-2675 1475);
FORCEPROP 1 LAST PATH I72
J 0
(-2675 1575);
DISPLAY 0.978723 (-2675 1575);
PAINT WHITE (-2675 1575);
DISPLAY INVISIBLE (-2675 1575);
FORCEPROP 0 LAST ROOM PROC_SIDEBAND
J 0
(-2675 1575);
DISPLAY 1.021277 (-2675 1575);
PAINT WHITE (-2675 1575);
DISPLAY INVISIBLE (-2675 1575);
FORCEADD OFFPAGE..5
R 2
(-1600 1425);
FORCEPROP 2 LAST $XR0 21 
J 0
(-1411 1425);
DISPLAY 0.638298 (-1411 1425);
PAINT MONO (-1411 1425);
FORCEPROP 2 LAST CDS_LIB mstr_standard
J 0
(-1600 1425);
PAINT ORANGE (-1600 1425);
DISPLAY INVISIBLE (-1600 1425);
FORCEPROP 1 LAST OFFPAGE TRUE
J 2
(-1925 1300);
PAINT GREEN (-1925 1300);
DISPLAY INVISIBLE (-1925 1300);
FORCEPROP 1 LAST COMMENT_BODY TRUE
J 2
(-1700 1350);
DISPLAY 1.170213 (-1700 1350);
PAINT PEACH (-1700 1350);
DISPLAY INVISIBLE (-1700 1350);
FORCEPROP 2 LAST PATH I74
J 0
(-1425 1500);
DISPLAY 1.021277 (-1425 1500);
PAINT ORANGE (-1425 1500);
DISPLAY INVISIBLE (-1425 1500);
FORCEADD RES..1
(-2600 800);
FORCEPROP 1 LAST LOCATION R4C10
J 0
(-2650 850);
DISPLAY 0.617021 (-2650 850);
PAINT AQUA (-2650 850);
FORCEPROP 1 LAST PART_NUMBER G21796-294
J 0
(-3025 750);
DISPLAY 0.617021 (-3025 750);
PAINT BLUE (-3025 750);
FORCEPROP 1 LAST VALUE 240
J 2
(-2650 750);
DISPLAY 0.617021 (-2650 750);
PAINT SKYBLUE (-2650 750);
FORCEPROP 1 LAST TOLERANCE 1.0%
J 0
(-2550 750);
DISPLAY 0.617021 (-2550 750);
PAINT SKYBLUE (-2550 750);
FORCEPROP 1 LAST PACK_TYPE 0402
J 0
(-2225 750);
DISPLAY 0.617021 (-2225 750);
PAINT SKYBLUE (-2225 750);
FORCEPROP 1 LAST MATERIAL CHIP
J 0
(-2125 750);
DISPLAY 0.617021 (-2125 750);
PAINT SKYBLUE (-2125 750);
FORCEPROP 1 LAST WATTAGE 1/16W
J 2
(-2275 750);
DISPLAY 0.617021 (-2275 750);
PAINT SKYBLUE (-2275 750);
FORCEPROP 1 LASTPIN (-2500 800) $PN 2
J 0
(-2538 812);
DISPLAY 0.617021 (-2538 812);
PAINT WHITE (-2538 812);
FORCEPROP 1 LASTPIN (-2700 800) $PN 1
J 0
(-2688 812);
DISPLAY 0.617021 (-2688 812);
PAINT WHITE (-2688 812);
FORCEPROP 2 LAST SEC_TYPE 0402
J 0
(-2650 1000);
DISPLAY 1.021277 (-2650 1000);
PAINT ORANGE (-2650 1000);
DISPLAY INVISIBLE (-2650 1000);
FORCEPROP 2 LAST CDS_LIB mstr_discrete
J 0
(-2600 800);
PAINT ORANGE (-2600 800);
DISPLAY INVISIBLE (-2600 800);
FORCEPROP 0 LAST BOM_COST PROC_SIDEBAND
J 0
(-2650 1050);
DISPLAY 1.021277 (-2650 1050);
PAINT WHITE (-2650 1050);
DISPLAY INVISIBLE (-2650 1050);
FORCEPROP 2 LAST SEC 1
J 0
(-2650 1000);
DISPLAY 0.680851 (-2650 1000);
PAINT MONO (-2650 1000);
DISPLAY INVISIBLE (-2650 1000);
FORCEPROP 2 LAST CDS_LOCATION R4C10
J 0
(-2650 850);
DISPLAY 0.617021 (-2650 850);
PAINT AQUA (-2650 850);
DISPLAY INVISIBLE (-2650 850);
FORCEPROP 1 LAST PATH I76
J 0
(-2650 950);
DISPLAY 0.978723 (-2650 950);
PAINT WHITE (-2650 950);
DISPLAY INVISIBLE (-2650 950);
FORCEPROP 0 LAST ROOM PROC_SIDEBAND
J 0
(-2650 950);
DISPLAY 1.021277 (-2650 950);
PAINT WHITE (-2650 950);
DISPLAY INVISIBLE (-2650 950);
FORCEADD OFFPAGE..5
R 2
(-1575 800);
FORCEPROP 2 LAST $XR0 55 
J 0
(-1386 800);
DISPLAY 0.638298 (-1386 800);
PAINT MONO (-1386 800);
FORCEPROP 2 LAST CDS_LIB mstr_standard
J 0
(-1575 800);
PAINT ORANGE (-1575 800);
DISPLAY INVISIBLE (-1575 800);
FORCEPROP 1 LAST OFFPAGE TRUE
J 2
(-1900 675);
PAINT GREEN (-1900 675);
DISPLAY INVISIBLE (-1900 675);
FORCEPROP 1 LAST COMMENT_BODY TRUE
J 2
(-1675 725);
DISPLAY 1.170213 (-1675 725);
PAINT PEACH (-1675 725);
DISPLAY INVISIBLE (-1675 725);
FORCEPROP 2 LAST PATH I77
J 0
(-1400 875);
DISPLAY 1.021277 (-1400 875);
PAINT ORANGE (-1400 875);
DISPLAY INVISIBLE (-1400 875);
FORCEADD PVCCIO_CPU1..1
(-3075 1000);
FORCEPROP 3 LASTPIN (-3075 950) SIG_NAME PVCCIO_CPU1\g
J 0
(-3065 960);
DISPLAY 0.659574 (-3065 960);
PAINT MONO (-3065 960);
DISPLAY INVISIBLE (-3065 960);
FORCEPROP 1 LAST VOLTAGE 1.1V
J 0
(-3120 957);
DISPLAY 0.340426 (-3120 957);
PAINT SKYBLUE (-3120 957);
DISPLAY INVISIBLE (-3120 957);
FORCEPROP 2 LAST CDS_LIB mstr_symbols
J 0
(-3075 1000);
PAINT ORANGE (-3075 1000);
DISPLAY INVISIBLE (-3075 1000);
FORCEPROP 1 LAST BODY_TYPE PLUMBING
J 0
(-3120 957);
DISPLAY 0.340426 (-3120 957);
PAINT GREEN (-3120 957);
DISPLAY INVISIBLE (-3120 957);
FORCEPROP 1 LAST PATH I78
J 0
(-3025 1025);
DISPLAY 0.872340 (-3025 1025);
PAINT AQUA (-3025 1025);
DISPLAY INVISIBLE (-3025 1025);
FORCEPROP 1 LAST HDL_POWER PVCCIO_CPU1
J 1
(-3075 1050);
DISPLAY 0.872340 (-3075 1050);
PAINT GREEN (-3075 1050);
DISPLAY INVISIBLE (-3075 1050);
FORCEADD RES..1
(-2375 3175);
FORCEPROP 1 LAST PART_NUMBER G21796-016
J 0
(-2425 3275);
DISPLAY 0.617021 (-2425 3275);
PAINT BLUE (-2425 3275);
FORCEPROP 1 LAST LOCATION R4P5
J 0
(-2425 3225);
DISPLAY 0.617021 (-2425 3225);
PAINT AQUA (-2425 3225);
FORCEPROP 1 LAST VALUE 10.0K
J 2
(-2400 3075);
DISPLAY 0.617021 (-2400 3075);
PAINT SKYBLUE (-2400 3075);
FORCEPROP 1 LAST TOLERANCE 1%
J 0
(-2375 3075);
DISPLAY 0.617021 (-2375 3075);
PAINT SKYBLUE (-2375 3075);
FORCEPROP 1 LAST PACK_TYPE 0402
J 0
(-2125 3025);
DISPLAY 0.617021 (-2125 3025);
PAINT SKYBLUE (-2125 3025);
FORCEPROP 1 LAST MATERIAL CHIP
J 0
(-2375 3025);
DISPLAY 0.617021 (-2375 3025);
PAINT SKYBLUE (-2375 3025);
FORCEPROP 1 LAST WATTAGE 1/16W
J 2
(-2400 3025);
DISPLAY 0.617021 (-2400 3025);
PAINT SKYBLUE (-2400 3025);
FORCEPROP 1 LASTPIN (-2275 3175) $PN 2
J 0
(-2313 3187);
DISPLAY 0.617021 (-2313 3187);
PAINT ORANGE (-2313 3187);
FORCEPROP 1 LASTPIN (-2475 3175) $PN 1
J 0
(-2463 3187);
DISPLAY 0.617021 (-2463 3187);
PAINT ORANGE (-2463 3187);
FORCEPROP 2 LAST CDS_LIB mstr_discrete
J 0
(-2375 3175);
PAINT ORANGE (-2375 3175);
DISPLAY INVISIBLE (-2375 3175);
FORCEPROP 2 LAST SEC_TYPE 0402
J 0
(-2425 3375);
DISPLAY 1.021277 (-2425 3375);
PAINT ORANGE (-2425 3375);
DISPLAY INVISIBLE (-2425 3375);
FORCEPROP 2 LAST SEC 1
J 0
(-2425 3375);
DISPLAY 0.680851 (-2425 3375);
PAINT MONO (-2425 3375);
DISPLAY INVISIBLE (-2425 3375);
FORCEPROP 2 LAST CDS_LOCATION R4P5
J 0
(-2425 3225);
DISPLAY 0.617021 (-2425 3225);
PAINT AQUA (-2425 3225);
DISPLAY INVISIBLE (-2425 3225);
FORCEPROP 1 LAST PATH I80
J 0
(-2425 3325);
DISPLAY 0.978723 (-2425 3325);
PAINT WHITE (-2425 3325);
DISPLAY INVISIBLE (-2425 3325);
FORCEPROP 0 LAST ROOM CPU0
J 0
(-2425 3375);
DISPLAY 1.021277 (-2425 3375);
PAINT ORANGE (-2425 3375);
DISPLAY INVISIBLE (-2425 3375);
FORCEADD RES..1
(-2375 2825);
FORCEPROP 1 LAST LOCATION R7P13
J 0
(-2425 2875);
DISPLAY 0.617021 (-2425 2875);
PAINT AQUA (-2425 2875);
FORCEPROP 1 LAST PART_NUMBER G21796-016
J 0
(-2425 2925);
DISPLAY 0.617021 (-2425 2925);
PAINT BLUE (-2425 2925);
FORCEPROP 1 LAST VALUE 10.0K
J 2
(-2400 2725);
DISPLAY 0.617021 (-2400 2725);
PAINT SKYBLUE (-2400 2725);
FORCEPROP 1 LAST TOLERANCE 1%
J 0
(-2375 2725);
DISPLAY 0.617021 (-2375 2725);
PAINT SKYBLUE (-2375 2725);
FORCEPROP 1 LAST PACK_TYPE 0402
J 0
(-2125 2675);
DISPLAY 0.617021 (-2125 2675);
PAINT SKYBLUE (-2125 2675);
FORCEPROP 1 LAST MATERIAL CHIP
J 0
(-2375 2675);
DISPLAY 0.617021 (-2375 2675);
PAINT SKYBLUE (-2375 2675);
FORCEPROP 1 LAST WATTAGE 1/16W
J 2
(-2400 2675);
DISPLAY 0.617021 (-2400 2675);
PAINT SKYBLUE (-2400 2675);
FORCEPROP 1 LASTPIN (-2275 2825) $PN 2
J 0
(-2313 2837);
DISPLAY 0.617021 (-2313 2837);
PAINT ORANGE (-2313 2837);
FORCEPROP 1 LASTPIN (-2475 2825) $PN 1
J 0
(-2463 2837);
DISPLAY 0.617021 (-2463 2837);
PAINT ORANGE (-2463 2837);
FORCEPROP 2 LAST CDS_LIB mstr_discrete
J 0
(-2375 2825);
PAINT ORANGE (-2375 2825);
DISPLAY INVISIBLE (-2375 2825);
FORCEPROP 2 LAST SEC_TYPE 0402
J 0
(-2425 3025);
DISPLAY 1.021277 (-2425 3025);
PAINT ORANGE (-2425 3025);
DISPLAY INVISIBLE (-2425 3025);
FORCEPROP 2 LAST SEC 1
J 0
(-2425 3025);
DISPLAY 0.680851 (-2425 3025);
PAINT MONO (-2425 3025);
DISPLAY INVISIBLE (-2425 3025);
FORCEPROP 2 LAST CDS_LOCATION R7P13
J 0
(-2425 2875);
DISPLAY 0.617021 (-2425 2875);
PAINT AQUA (-2425 2875);
DISPLAY INVISIBLE (-2425 2875);
FORCEPROP 1 LAST PATH I81
J 0
(-2425 2975);
DISPLAY 0.978723 (-2425 2975);
PAINT WHITE (-2425 2975);
DISPLAY INVISIBLE (-2425 2975);
FORCEPROP 0 LAST ROOM CPU1
J 0
(-2425 3025);
DISPLAY 1.021277 (-2425 3025);
PAINT ORANGE (-2425 3025);
DISPLAY INVISIBLE (-2425 3025);
FORCEADD GND..1
(-3075 2425);
FORCEPROP 3 LASTPIN (-3075 2475) SIG_NAME GND\g
J 0
(-3065 2485);
DISPLAY 0.659574 (-3065 2485);
PAINT MONO (-3065 2485);
DISPLAY INVISIBLE (-3065 2485);
FORCEPROP 1 LAST VOLTAGE 0.0V
J 0
(-3120 2382);
DISPLAY 0.340426 (-3120 2382);
PAINT SKYBLUE (-3120 2382);
DISPLAY INVISIBLE (-3120 2382);
FORCEPROP 1 LAST SIZE 1B
J 0
(-3000 2375);
DISPLAY 1.170213 (-3000 2375);
PAINT AQUA (-3000 2375);
DISPLAY INVISIBLE (-3000 2375);
FORCEPROP 2 LAST CDS_LIB mstr_symbols
J 0
(-3075 2425);
PAINT ORANGE (-3075 2425);
DISPLAY INVISIBLE (-3075 2425);
FORCEPROP 1 LAST BODY_TYPE PLUMBING
J 0
(-3120 2382);
DISPLAY 0.340426 (-3120 2382);
PAINT GREEN (-3120 2382);
DISPLAY INVISIBLE (-3120 2382);
FORCEPROP 1 LAST PATH I82
J 0
(-3000 2425);
DISPLAY 0.872340 (-3000 2425);
PAINT AQUA (-3000 2425);
DISPLAY INVISIBLE (-3000 2425);
FORCEPROP 1 LAST HDL_POWER GND
J 0
(-3075 2575);
DISPLAY 1.170213 (-3075 2575);
PAINT GREEN (-3075 2575);
DISPLAY INVISIBLE (-3075 2575);
FORCEADD OFFPAGE..5
R 2
(-1175 2825);
FORCEPROP 2 LAST $XR0 73 
J 0
(-986 2825);
DISPLAY 0.638298 (-986 2825);
PAINT MONO (-986 2825);
FORCEPROP 2 LAST CDS_LIB mstr_standard
J 0
(-1175 2825);
PAINT ORANGE (-1175 2825);
DISPLAY INVISIBLE (-1175 2825);
FORCEPROP 1 LAST OFFPAGE TRUE
J 2
(-1500 2700);
PAINT GREEN (-1500 2700);
DISPLAY INVISIBLE (-1500 2700);
FORCEPROP 1 LAST COMMENT_BODY TRUE
J 2
(-1275 2750);
DISPLAY 1.170213 (-1275 2750);
PAINT PEACH (-1275 2750);
DISPLAY INVISIBLE (-1275 2750);
FORCEPROP 2 LAST PATH I83
J 0
(-1000 2900);
DISPLAY 1.021277 (-1000 2900);
PAINT ORANGE (-1000 2900);
DISPLAY INVISIBLE (-1000 2900);
FORCEADD OFFPAGE..5
R 2
(-1175 3175);
FORCEPROP 2 LAST $XR0 39 
J 0
(-986 3175);
DISPLAY 0.638298 (-986 3175);
PAINT MONO (-986 3175);
FORCEPROP 2 LAST CDS_LIB mstr_standard
J 0
(-1175 3175);
PAINT ORANGE (-1175 3175);
DISPLAY INVISIBLE (-1175 3175);
FORCEPROP 1 LAST OFFPAGE TRUE
J 2
(-1500 3050);
PAINT GREEN (-1500 3050);
DISPLAY INVISIBLE (-1500 3050);
FORCEPROP 1 LAST COMMENT_BODY TRUE
J 2
(-1275 3100);
DISPLAY 1.170213 (-1275 3100);
PAINT PEACH (-1275 3100);
DISPLAY INVISIBLE (-1275 3100);
FORCEPROP 2 LAST PATH I84
J 0
(-1000 3250);
DISPLAY 1.021277 (-1000 3250);
PAINT ORANGE (-1000 3250);
DISPLAY INVISIBLE (-1000 3250);
FORCEADD PVCCIO_CPU0..1
(-1200 4775);
FORCEPROP 3 LASTPIN (-1200 4725) SIG_NAME PVCCIO_CPU0\g
J 0
(-1190 4735);
DISPLAY 0.659574 (-1190 4735);
PAINT MONO (-1190 4735);
DISPLAY INVISIBLE (-1190 4735);
FORCEPROP 1 LAST VOLTAGE 1.1V
J 0
(-1245 4732);
DISPLAY 0.340426 (-1245 4732);
PAINT SKYBLUE (-1245 4732);
DISPLAY INVISIBLE (-1245 4732);
FORCEPROP 2 LAST CDS_LIB mstr_symbols
J 0
(-1200 4775);
PAINT ORANGE (-1200 4775);
DISPLAY INVISIBLE (-1200 4775);
FORCEPROP 1 LAST BODY_TYPE PLUMBING
J 0
(-1245 4732);
DISPLAY 0.340426 (-1245 4732);
PAINT GREEN (-1245 4732);
DISPLAY INVISIBLE (-1245 4732);
FORCEPROP 1 LAST PATH I85
J 0
(-1150 4800);
DISPLAY 0.872340 (-1150 4800);
PAINT AQUA (-1150 4800);
DISPLAY INVISIBLE (-1150 4800);
FORCEPROP 1 LAST HDL_POWER PVCCIO_CPU0
J 1
(-1200 4825);
DISPLAY 0.872340 (-1200 4825);
PAINT GREEN (-1200 4825);
DISPLAY INVISIBLE (-1200 4825);
FORCEADD CAD_NOTE..1
(-2000 5050);
FORCEPROP 0 LAST L1 PLACE R4R4 NEAR CPU0, AND R7P20 NEAR CPU1.
J 0
(-2550 4925);
PAINT WHITE (-2550 4925);
FORCEPROP 2 LAST BOM_COST MIO_CHASSIS
J 0
(-2150 5000);
PAINT WHITE (-2150 5000);
DISPLAY INVISIBLE (-2150 5000);
FORCEPROP 2 LAST CDS_LIB mstr_symbols
J 0
(-2000 5050);
PAINT WHITE (-2000 5050);
DISPLAY INVISIBLE (-2000 5050);
FORCEPROP 1 LAST COMMENT_BODY TRUE
J 0
(-1975 5150);
DISPLAY 1.319149 (-1975 5150);
PAINT WHITE (-1975 5150);
DISPLAY INVISIBLE (-1975 5150);
FORCEPROP 2 LAST ROOM ST_SATA
J 0
(-2150 5000);
PAINT WHITE (-2150 5000);
DISPLAY INVISIBLE (-2150 5000);
FORCEADD INTEL_CORP_BPAGE..1
(4250 200);
FORCEPROP 1 LAST CDS_CON_LAST_MODIFIED Tue Dec 01 11:51:49 2015
J 0
(2825 525);
PAINT ORANGE (2825 525);
DISPLAY INVISIBLE (2825 525);
FORCEPROP 1 LAST CUSTOM_TXT_CDS <CURRENT_DESIGN_SHEET> OF <TOTAL_DESIGN_SHEETS>
J 0
(3750 225);
PAINT GREEN (3750 225);
FORCEPROP 1 LAST CUSTOM_TXT_CDS <CON_LAST_MODIFIED>
J 0
(2325 550);
PAINT GREEN (2325 550);
FORCEPROP 2 LAST CUSTOM_TXT_CDS <XR_PAGE_TITLE>
J 0
(-3640 5450);
DISPLAY 0.638298 (-3640 5450);
PAINT PINK (-3640 5450);
DISPLAY INVISIBLE (-3640 5450);
FORCEPROP 1 LAST SCH_ADDRESS3 Santa Clara, CA 95052-8119
J 0
(275 225);
DISPLAY 0.617021 (275 225);
PAINT YELLOW (275 225);
FORCEPROP 1 LAST SCH_ADDRESS2 P.O. BOX 58119
J 0
(275 275);
DISPLAY 0.617021 (275 275);
PAINT YELLOW (275 275);
FORCEPROP 1 LAST SCH_ADDRESS1 2200 Mission College Blvd.
J 0
(275 325);
DISPLAY 0.617021 (275 325);
PAINT YELLOW (275 325);
FORCEPROP 1 LAST SCH_TITLE CPU SIDE BAND:PULL-UPS/PULL-DOWNS
J 0
(-3700 250);
DISPLAY 1.212766 (-3700 250);
PAINT YELLOW (-3700 250);
FORCEPROP 1 LAST SCH_NUMBER H4694802
J 0
(2950 350);
DISPLAY 1.212766 (2950 350);
PAINT YELLOW (2950 350);
FORCEPROP 1 LAST SCH_DEPT BESD
J 1
(-200 300);
DISPLAY 1.212766 (-200 300);
PAINT YELLOW (-200 300);
FORCEPROP 1 LAST SCH_REV 2.420
J 0
(4000 350);
DISPLAY 0.978723 (4000 350);
PAINT YELLOW (4000 350);
FORCEPROP 2 LAST PAGE_BORDER TRUE
J 0
(-3640 5450);
DISPLAY 0.638298 (-3640 5450);
PAINT PINK (-3640 5450);
DISPLAY INVISIBLE (-3640 5450);
FORCEPROP 2 LAST CDS_LIB mstr_symbols
J 0
(4250 200);
PAINT MONO (4250 200);
DISPLAY INVISIBLE (4250 200);
FORCEPROP 1 LAST COMMENT_BODY TRUE
J 0
(4262 212);
DISPLAY 0.468085 (4262 212);
PAINT PEACH (4262 212);
DISPLAY INVISIBLE (4262 212);
FORCEPROP 2 LAST CDS_XR_PAGE_TITLE CR-97 : @BASEBOARD_FAB2_LIB.BASEBOARD_FAB2(SCH_1):PAGE97
J 0
(-3640 5450);
DISPLAY 0.638298 (-3640 5450);
PAINT PINK (-3640 5450);
DISPLAY INVISIBLE (-3640 5450);
WIRE 16 -1 (-2700 4625)(-2700 4725);
WIRE 16 -1 (-3100 1425)(-2725 1425);
WIRE 16 -1 (-3100 1575)(-3100 1425);
WIRE 16 -1 (-3075 800)(-2700 800);
WIRE 16 -1 (-3075 950)(-3075 800);
WIRE 16 -1 (-2475 3175)(-3075 3175);
WIRE 16 -1 (-3075 3175)(-3075 2825);
WIRE 16 -1 (-2475 2825)(-3075 2825);
WIRE 16 -1 (-3075 2825)(-3075 2475);
WIRE 16 -1 (-1200 4625)(-1200 4725);
WIRE 16 273 (150 3950)(-3675 3950);
WIRE 16 -1 (-2700 4425)(-2700 4225);
WIRE 16 -1 (-2700 4225)(-2100 4225);
WIRE 16 -1 (-3350 4225)(-2700 4225);
FORCEPROP 2 LAST SIG_NAME H_CPU0_FAST_WAKE_N
J 0
(-3275 4235);
DISPLAY 0.617021 (-3275 4235);
PAINT ORANGE (-3275 4235);
WIRE 16 273 (150 1950)(-3675 1950);
WIRE 16 -1 (-2525 1425)(-1650 1425);
FORCEPROP 2 LAST SIG_NAME PU_CPU0_TSC_SYNC
J 0
(-2200 1435);
DISPLAY 0.617021 (-2200 1435);
PAINT ORANGE (-2200 1435);
WIRE 16 -1 (-2500 800)(-1625 800);
FORCEPROP 2 LAST SIG_NAME PU_CPU1_TSC_SYNC
J 0
(-2175 810);
DISPLAY 0.617021 (-2175 810);
PAINT ORANGE (-2175 810);
WIRE 16 -1 (-1225 2825)(-2275 2825);
FORCEPROP 0 LAST SIG_NAME PD_CPU1_MCP01_DMON
J 0
(-1810 2835);
DISPLAY 0.617021 (-1810 2835);
PAINT ORANGE (-1810 2835);
WIRE 16 -1 (-2275 3175)(-1225 3175);
FORCEPROP 0 LAST SIG_NAME PD_CPU0_MCP01_DMON
J 0
(-1810 3185);
DISPLAY 0.617021 (-1810 3185);
PAINT ORANGE (-1810 3185);
WIRE 16 -1 (-3325 4475)(-3325 4300);
WIRE 16 -1 (-3325 4475)(-3625 4475);
WIRE 16 -1 (-3325 4300)(-3625 4300);
WIRE 16 -1 (-3625 4475)(-3625 4300);
WIRE 16 -1 (-3350 4450)(-3350 4325);
WIRE 16 -1 (-3350 4450)(-3600 4450);
WIRE 16 -1 (-3600 4325)(-3350 4325);
WIRE 16 -1 (-3600 4450)(-3600 4325);
WIRE 16 -1 (-1200 4225)(-325 4225);
FORCEPROP 2 LAST SIG_NAME H_CPU1_FAST_WAKE_N
J 0
(-1075 4235);
DISPLAY 0.617021 (-1075 4235);
PAINT ORANGE (-1075 4235);
WIRE 16 -1 (-1200 4425)(-1200 4225);
WIRE 16 -1 (-1200 4225)(-1900 4225);
WIRE 16 -1 (175 4500)(175 4325);
WIRE 16 -1 (175 4500)(-125 4500);
WIRE 16 -1 (175 4325)(-125 4325);
WIRE 16 -1 (-125 4500)(-125 4325);
WIRE 16 -1 (150 4475)(150 4350);
WIRE 16 -1 (150 4475)(-100 4475);
WIRE 16 -1 (-100 4350)(150 4350);
WIRE 16 -1 (-100 4475)(-100 4350);
WIRE 16 273 (250 575)(250 5150);
WIRE 16 273 (4150 2775)(325 2775);
DOT 1 (-3075 2825);
DOT 1 (-1200 4225);
DOT 1 (-2700 4225);
FORCENOTE
ROOM=PROC_SIDEBAND
(-3687 433) 0;
DISPLAY LEFT (-3687 433);
DISPLAY 1.276596 (-3687 433);
PAINT PURPLE (-3687 433);
FORCENOTE
BOM_COST=PROC_SIDEBAND
(-3675 350) 0;
DISPLAY LEFT (-3675 350);
DISPLAY 1.276596 (-3675 350);
PAINT PURPLE (-3675 350);
FORCENOTE
CPU0
(-3525 4350) 0;
DISPLAY LEFT (-3525 4350);
DISPLAY 0.808511 (-3525 4350);
PAINT PURPLE (-3525 4350);
FORCENOTE
TO/FROM
(-3575 4400) 0;
DISPLAY LEFT (-3575 4400);
DISPLAY 0.638298 (-3575 4400);
PAINT PURPLE (-3575 4400);
FORCENOTE
CPU1
(-25 4375) 0;
DISPLAY LEFT (-25 4375);
DISPLAY 0.808511 (-25 4375);
PAINT PURPLE (-25 4375);
FORCENOTE
TO/FROM
(-75 4425) 0;
DISPLAY LEFT (-75 4425);
DISPLAY 0.638298 (-75 4425);
PAINT PURPLE (-75 4425);
QUIT
